(kicad_pcb
	(version 20211014)
	(generator pcbnew)
	(general
    (thickness 1.6)
  )
	(paper "A4")
	(title_block
    (title "SA800U (Snapdragon 845) Baseboard")
    (date "2023-10-19")
    (rev "1.0.3")
    (company "Antmicro Ltd.")
    (comment 1 "www.antmicro.com")
		(comment 9 "footprints 462-471 of 589")
	)
	(layers
    (0 "F.Cu" signal)
    (1 "In1.Cu" power)
    (2 "In2.Cu" signal)
    (3 "In3.Cu" signal)
    (4 "In4.Cu" power)
    (31 "B.Cu" signal)
    (32 "B.Adhes" user "B.Adhesive")
    (33 "F.Adhes" user "F.Adhesive")
    (34 "B.Paste" user)
    (35 "F.Paste" user)
    (36 "B.SilkS" user "B.Silkscreen")
    (37 "F.SilkS" user "F.Silkscreen")
    (38 "B.Mask" user)
    (39 "F.Mask" user)
    (40 "Dwgs.User" user "User.Drawings")
    (41 "Cmts.User" user "User.Comments")
    (42 "Eco1.User" user "User.Eco1")
    (43 "Eco2.User" user "User.Eco2")
    (44 "Edge.Cuts" user)
    (45 "Margin" user)
    (46 "B.CrtYd" user "B.Courtyard")
    (47 "F.CrtYd" user "F.Courtyard")
    (48 "B.Fab" user)
    (49 "F.Fab" user)
  )
	(footprint "sa800u-baseboard-hw-footprints:C_0402_1005Metric" (layer "B.Cu")
    (tedit 616D63CF)
    (at 133.888164 125.012952 90)
    (descr "Capacitor SMD 0402")
    (tags "capacitor SMD 0402")
    (property "Author" "Antmicro")
    (property "Dielectric" "X5R")
    (property "License" "Apache-2.0")
    (property "MPN" "GRM155R61H104KE14D")
    (property "Manufacturer" "Murata")
    (property "Sheetfile" "hdmi-converter.kicad_sch")
    (property "Sheetname" "HDMI converter")
    (property "Val" "100n")
    (property "Voltage" "50V")
    (attr smd)
    (fp_text reference "C20" (at 1.112952 -0.588164 270) (layer "B.SilkS")
      (effects (font (size 0.7 0.7) (thickness 0.15)) (justify left bottom mirror))
    )
    (fp_text value "C_100n_0402" (at 0 -1.4 270) (layer "B.Fab")
      (effects (font (size 0.7 0.7) (thickness 0.15)) (justify left bottom mirror))
    )
    (fp_text user "${REFERENCE}" (at -0.932 -3.168 270) (layer "B.Fab") hide
      (effects (font (size 0.7 0.7) (thickness 0.15)) (justify left bottom mirror))
    )
    (fp_text user "License: Apache-2.0" (at -0.932 -5.17 270) (layer "B.Fab") hide
      (effects (font (size 0.7 0.7) (thickness 0.15)) (justify left bottom mirror))
    )
    (fp_text user "Author: Antmicro" (at -0.932 -4.17 270) (layer "B.Fab") hide
      (effects (font (size 0.7 0.7) (thickness 0.15)) (justify left bottom mirror))
    )
    (fp_rect (start -0.94 0.47) (end 0.94 -0.47) (layer "B.CrtYd") (width 0.05) (fill none))
    (fp_rect (start -0.499 0.249) (end 0.499 -0.249) (layer "B.Fab") (width 0.15) (fill none))
    (pad "1" smd roundrect (at -0.484 0 90) (size 0.59 0.64) (layers "B.Cu" "B.Paste" "B.Mask") (roundrect_rratio 0.25)
      (net 131 "3V3_SYS") (pintype "passive"))
    (pad "2" smd roundrect (at 0.484 0 90) (size 0.59 0.64) (layers "B.Cu" "B.Paste" "B.Mask") (roundrect_rratio 0.25)
      (net 1 "GND") (pintype "passive"))
  )
	(footprint "sa800u-baseboard-hw-footprints:C_0805_2012Metric" (layer "B.Cu")
    (tedit 5FD9C126)
    (at 77.2 101.9 90)
    (descr "Capacitor SMD 0805")
    (tags "capacitor SMD 0805")
    (property "Author" "Antmicro")
    (property "Dielectric" "")
    (property "License" "Apache-2.0")
    (property "MPN" "GRM21BR60J107ME15L")
    (property "Manufacturer" "Murata")
    (property "Sheetfile" "poe.kicad_sch")
    (property "Sheetname" "PoE")
    (property "Val" "100u")
    (property "Voltage" "")
    (attr smd)
    (fp_text reference "C148" (at 4.48 0.35 270) (layer "B.SilkS")
      (effects (font (size 0.7 0.7) (thickness 0.15)) (justify left bottom mirror))
    )
    (fp_text value "C_100u_0805" (at 0 -1.947 270) (layer "B.Fab")
      (effects (font (size 0.7 0.7) (thickness 0.15)) (justify left bottom mirror))
    )
    (fp_text user "License: Apache-2.0" (at -1.9 -4.947 270) (layer "B.Fab") hide
      (effects (font (size 0.7 0.7) (thickness 0.15)) (justify left bottom mirror))
    )
    (fp_text user "Author: Antmicro" (at -1.9 -5.947 270) (layer "B.Fab") hide
      (effects (font (size 0.7 0.7) (thickness 0.15)) (justify left bottom mirror))
    )
    (fp_text user "${REFERENCE}" (at -1.9 -3.947 270) (layer "B.Fab") hide
      (effects (font (size 0.7 0.7) (thickness 0.15)) (justify left bottom mirror))
    )
    (fp_line (start -0.3 -0.8) (end 0.3 -0.8) (layer "B.SilkS") (width 0.15))
    (fp_line (start -0.3 0.8) (end 0.3 0.8) (layer "B.SilkS") (width 0.15))
    (fp_rect (start -1.9 0.93) (end 1.9 -0.93) (layer "B.CrtYd") (width 0.05) (fill none))
    (fp_rect (start -0.95 0.675) (end 0.95 -0.675) (layer "B.Fab") (width 0.15) (fill none))
    (pad "1" smd rect (at -1.05 0 90) (size 1.2 1.2) (layers "B.Cu" "B.Paste" "B.Mask")
      (net 136 "5V_POE") (pintype "passive"))
    (pad "2" smd rect (at 1.05 0 90) (size 1.2 1.2) (layers "B.Cu" "B.Paste" "B.Mask")
      (net 1 "GND") (pintype "passive"))
  )
	(footprint "sa800u-baseboard-hw-footprints:C_0603_1608Metric" (layer "B.Cu")
    (tedit 5D5E94D2)
    (at 76.6 145.3 180)
    (descr "Capacitor SMD 0603")
    (tags "capacitor 0603")
    (property "Author" "Antmicro")
    (property "Dielectric" "")
    (property "License" "Apache-2.0")
    (property "MPN" "C1608X5R1E106M080AC")
    (property "Manufacturer" "TDK")
    (property "Sheetfile" "psu.kicad_sch")
    (property "Sheetname" "PSU")
    (property "Val" "10u/25V")
    (property "Voltage" "")
    (attr smd)
    (fp_text reference "C121" (at -1.43 -2.86) (layer "B.SilkS")
      (effects (font (size 0.7 0.7) (thickness 0.15)) (justify left bottom mirror))
    )
    (fp_text value "C_10u_25V_0603" (at 0 -1.6) (layer "B.Fab")
      (effects (font (size 0.7 0.7) (thickness 0.15)) (justify left bottom mirror))
    )
    (fp_text user "License: Apache-2.0" (at -1.682 -5.895) (layer "B.Fab") hide
      (effects (font (size 0.7 0.7) (thickness 0.15)) (justify left bottom mirror))
    )
    (fp_text user "${REFERENCE}" (at -1.682 -3.895) (layer "B.Fab") hide
      (effects (font (size 0.7 0.7) (thickness 0.15)) (justify left bottom mirror))
    )
    (fp_text user "Author: Antmicro" (at -1.682 -4.894) (layer "B.Fab") hide
      (effects (font (size 0.7 0.7) (thickness 0.15)) (justify left bottom mirror))
    )
    (fp_line (start -0.3 0.3) (end 0.3 0.3) (layer "B.SilkS") (width 0.15))
    (fp_line (start -0.3 -0.3) (end 0.3 -0.3) (layer "B.SilkS") (width 0.15))
    (fp_rect (start -1.24 0.7) (end 1.24 -0.7) (layer "B.CrtYd") (width 0.05) (fill none))
    (fp_rect (start -0.8 0.4) (end 0.8 -0.4) (layer "B.Fab") (width 0.15) (fill none))
    (pad "1" smd roundrect (at -0.7 0 180) (size 0.6 0.8) (layers "B.Cu" "B.Paste" "B.Mask") (roundrect_rratio 0.2)
      (net 152 "/PSU/AUX_VDD") (pintype "passive"))
    (pad "2" smd roundrect (at 0.7 0 180) (size 0.6 0.8) (layers "B.Cu" "B.Paste" "B.Mask") (roundrect_rratio 0.2)
      (net 1 "GND") (pintype "passive"))
  )
	(footprint "sa800u-baseboard-hw-footprints:C_0603_1608Metric" (layer "B.Cu")
    (tedit 5D5E94D2)
    (at 76.6 146.8 180)
    (descr "Capacitor SMD 0603")
    (tags "capacitor 0603")
    (property "Author" "Antmicro")
    (property "Dielectric" "")
    (property "License" "Apache-2.0")
    (property "MPN" "C1608X5R1E106M080AC")
    (property "Manufacturer" "TDK")
    (property "Sheetfile" "psu.kicad_sch")
    (property "Sheetname" "PSU")
    (property "Val" "10u/25V")
    (property "Voltage" "")
    (attr smd)
    (fp_text reference "C122" (at -1.42 -2.32) (layer "B.SilkS")
      (effects (font (size 0.7 0.7) (thickness 0.15)) (justify left bottom mirror))
    )
    (fp_text value "C_10u_25V_0603" (at 0 -1.6) (layer "B.Fab")
      (effects (font (size 0.7 0.7) (thickness 0.15)) (justify left bottom mirror))
    )
    (fp_text user "${REFERENCE}" (at -1.682 -3.895) (layer "B.Fab") hide
      (effects (font (size 0.7 0.7) (thickness 0.15)) (justify left bottom mirror))
    )
    (fp_text user "Author: Antmicro" (at -1.682 -4.894) (layer "B.Fab") hide
      (effects (font (size 0.7 0.7) (thickness 0.15)) (justify left bottom mirror))
    )
    (fp_text user "License: Apache-2.0" (at -1.682 -5.895) (layer "B.Fab") hide
      (effects (font (size 0.7 0.7) (thickness 0.15)) (justify left bottom mirror))
    )
    (fp_line (start -0.3 0.3) (end 0.3 0.3) (layer "B.SilkS") (width 0.15))
    (fp_line (start -0.3 -0.3) (end 0.3 -0.3) (layer "B.SilkS") (width 0.15))
    (fp_rect (start -1.24 0.7) (end 1.24 -0.7) (layer "B.CrtYd") (width 0.05) (fill none))
    (fp_rect (start -0.8 0.4) (end 0.8 -0.4) (layer "B.Fab") (width 0.15) (fill none))
    (pad "1" smd roundrect (at -0.7 0 180) (size 0.6 0.8) (layers "B.Cu" "B.Paste" "B.Mask") (roundrect_rratio 0.2)
      (net 152 "/PSU/AUX_VDD") (pintype "passive"))
    (pad "2" smd roundrect (at 0.7 0 180) (size 0.6 0.8) (layers "B.Cu" "B.Paste" "B.Mask") (roundrect_rratio 0.2)
      (net 1 "GND") (pintype "passive"))
  )
	(footprint "sa800u-baseboard-hw-footprints:C_0603_1608Metric" (layer "B.Cu")
    (tedit 5D5E94D2)
    (at 82.65 127.59 90)
    (descr "Capacitor SMD 0603")
    (tags "capacitor 0603")
    (property "Author" "Antmicro")
    (property "Dielectric" "")
    (property "License" "Apache-2.0")
    (property "MPN" "C1608X5R1E106M080AC")
    (property "Manufacturer" "TDK")
    (property "Sheetfile" "psu.kicad_sch")
    (property "Sheetname" "PSU")
    (property "Val" "10u/25V")
    (property "Voltage" "")
    (attr smd)
    (fp_text reference "C126" (at -1.09 0.38 270) (layer "B.SilkS")
      (effects (font (size 0.7 0.7) (thickness 0.15)) (justify left bottom mirror))
    )
    (fp_text value "C_10u_25V_0603" (at 0 -1.6 270) (layer "B.Fab")
      (effects (font (size 0.7 0.7) (thickness 0.15)) (justify left bottom mirror))
    )
    (fp_text user "${REFERENCE}" (at -1.682 -3.895 270) (layer "B.Fab") hide
      (effects (font (size 0.7 0.7) (thickness 0.15)) (justify left bottom mirror))
    )
    (fp_text user "License: Apache-2.0" (at -1.682 -5.895 270) (layer "B.Fab") hide
      (effects (font (size 0.7 0.7) (thickness 0.15)) (justify left bottom mirror))
    )
    (fp_text user "Author: Antmicro" (at -1.682 -4.894 270) (layer "B.Fab") hide
      (effects (font (size 0.7 0.7) (thickness 0.15)) (justify left bottom mirror))
    )
    (fp_line (start -0.3 -0.3) (end 0.3 -0.3) (layer "B.SilkS") (width 0.15))
    (fp_line (start -0.3 0.3) (end 0.3 0.3) (layer "B.SilkS") (width 0.15))
    (fp_rect (start -1.24 0.7) (end 1.24 -0.7) (layer "B.CrtYd") (width 0.05) (fill none))
    (fp_rect (start -0.8 0.4) (end 0.8 -0.4) (layer "B.Fab") (width 0.15) (fill none))
    (pad "1" smd roundrect (at -0.7 0 90) (size 0.6 0.8) (layers "B.Cu" "B.Paste" "B.Mask") (roundrect_rratio 0.2)
      (net 74 "VDD") (pintype "passive"))
    (pad "2" smd roundrect (at 0.7 0 90) (size 0.6 0.8) (layers "B.Cu" "B.Paste" "B.Mask") (roundrect_rratio 0.2)
      (net 1 "GND") (pintype "passive"))
  )
	(footprint "sa800u-baseboard-hw-footprints:C_0805_2012Metric" (layer "B.Cu")
    (tedit 5FD9C126)
    (at 75.3 101.9 90)
    (descr "Capacitor SMD 0805")
    (tags "capacitor SMD 0805")
    (property "Author" "Antmicro")
    (property "Dielectric" "")
    (property "License" "Apache-2.0")
    (property "MPN" "GRM21BR60J107ME15L")
    (property "Manufacturer" "Murata")
    (property "Sheetfile" "poe.kicad_sch")
    (property "Sheetname" "PoE")
    (property "Val" "100u")
    (property "Voltage" "")
    (attr smd)
    (fp_text reference "C147" (at 4.48 0.35 270) (layer "B.SilkS")
      (effects (font (size 0.7 0.7) (thickness 0.15)) (justify left bottom mirror))
    )
    (fp_text value "C_100u_0805" (at 0 -1.947 270) (layer "B.Fab")
      (effects (font (size 0.7 0.7) (thickness 0.15)) (justify left bottom mirror))
    )
    (fp_text user "Author: Antmicro" (at -1.9 -5.947 270) (layer "B.Fab") hide
      (effects (font (size 0.7 0.7) (thickness 0.15)) (justify left bottom mirror))
    )
    (fp_text user "${REFERENCE}" (at -1.9 -3.947 270) (layer "B.Fab") hide
      (effects (font (size 0.7 0.7) (thickness 0.15)) (justify left bottom mirror))
    )
    (fp_text user "License: Apache-2.0" (at -1.9 -4.947 270) (layer "B.Fab") hide
      (effects (font (size 0.7 0.7) (thickness 0.15)) (justify left bottom mirror))
    )
    (fp_line (start -0.3 -0.8) (end 0.3 -0.8) (layer "B.SilkS") (width 0.15))
    (fp_line (start -0.3 0.8) (end 0.3 0.8) (layer "B.SilkS") (width 0.15))
    (fp_rect (start -1.9 0.93) (end 1.9 -0.93) (layer "B.CrtYd") (width 0.05) (fill none))
    (fp_rect (start -0.95 0.675) (end 0.95 -0.675) (layer "B.Fab") (width 0.15) (fill none))
    (pad "1" smd rect (at -1.05 0 90) (size 1.2 1.2) (layers "B.Cu" "B.Paste" "B.Mask")
      (net 136 "5V_POE") (pintype "passive"))
    (pad "2" smd rect (at 1.05 0 90) (size 1.2 1.2) (layers "B.Cu" "B.Paste" "B.Mask")
      (net 1 "GND") (pintype "passive"))
  )
	(footprint "sa800u-baseboard-hw-footprints:C_0603_1608Metric" (layer "B.Cu")
    (tedit 5D5E94D2)
    (at 84.15 127.6 90)
    (descr "Capacitor SMD 0603")
    (tags "capacitor 0603")
    (property "Author" "Antmicro")
    (property "Dielectric" "")
    (property "License" "Apache-2.0")
    (property "MPN" "C1608X5R1E106M080AC")
    (property "Manufacturer" "TDK")
    (property "Sheetfile" "psu.kicad_sch")
    (property "Sheetname" "PSU")
    (property "Val" "10u/25V")
    (property "Voltage" "")
    (attr smd)
    (fp_text reference "C127" (at -1.09 0.38 270) (layer "B.SilkS")
      (effects (font (size 0.7 0.7) (thickness 0.15)) (justify left bottom mirror))
    )
    (fp_text value "C_10u_25V_0603" (at 0 -1.6 270) (layer "B.Fab")
      (effects (font (size 0.7 0.7) (thickness 0.15)) (justify left bottom mirror))
    )
    (fp_text user "Author: Antmicro" (at -1.682 -4.894 270) (layer "B.Fab") hide
      (effects (font (size 0.7 0.7) (thickness 0.15)) (justify left bottom mirror))
    )
    (fp_text user "License: Apache-2.0" (at -1.682 -5.895 270) (layer "B.Fab") hide
      (effects (font (size 0.7 0.7) (thickness 0.15)) (justify left bottom mirror))
    )
    (fp_text user "${REFERENCE}" (at -1.682 -3.895 270) (layer "B.Fab") hide
      (effects (font (size 0.7 0.7) (thickness 0.15)) (justify left bottom mirror))
    )
    (fp_line (start -0.3 0.3) (end 0.3 0.3) (layer "B.SilkS") (width 0.15))
    (fp_line (start -0.3 -0.3) (end 0.3 -0.3) (layer "B.SilkS") (width 0.15))
    (fp_rect (start -1.24 0.7) (end 1.24 -0.7) (layer "B.CrtYd") (width 0.05) (fill none))
    (fp_rect (start -0.8 0.4) (end 0.8 -0.4) (layer "B.Fab") (width 0.15) (fill none))
    (pad "1" smd roundrect (at -0.7 0 90) (size 0.6 0.8) (layers "B.Cu" "B.Paste" "B.Mask") (roundrect_rratio 0.2)
      (net 74 "VDD") (pintype "passive"))
    (pad "2" smd roundrect (at 0.7 0 90) (size 0.6 0.8) (layers "B.Cu" "B.Paste" "B.Mask") (roundrect_rratio 0.2)
      (net 1 "GND") (pintype "passive"))
  )
	(footprint "sa800u-baseboard-hw-footprints:R_0402_1005Metric" (layer "B.Cu")
    (tedit 5FD9C158)
    (at 122.84 93.8 -90)
    (descr "Resistor SMD 0402")
    (tags "resistor SMD 0402")
    (property "Author" "Antmicro")
    (property "License" "Apache-2.0")
    (property "MPN" "CR0402-FX-33R0GLF")
    (property "Manufacturer" "Bourns")
    (property "Sheetfile" "other-interfaces.kicad_sch")
    (property "Sheetname" "Other Interfaces")
    (property "Tolerance" "1%")
    (property "Val" "33R")
    (attr smd)
    (fp_text reference "R102" (at 0.86 -0.47 90) (layer "B.SilkS")
      (effects (font (size 0.7 0.7) (thickness 0.15)) (justify left bottom mirror))
    )
    (fp_text value "R_33R_0402" (at 0 -1.4 90) (layer "B.Fab")
      (effects (font (size 0.7 0.7) (thickness 0.15)) (justify left bottom mirror))
    )
    (fp_text user "License: Apache-2.0" (at -0.95 -5.169 90) (layer "B.Fab") hide
      (effects (font (size 0.7 0.7) (thickness 0.15)) (justify left bottom mirror))
    )
    (fp_text user "Author: Antmicro" (at -0.95 -4.169 90) (layer "B.Fab") hide
      (effects (font (size 0.7 0.7) (thickness 0.15)) (justify left bottom mirror))
    )
    (fp_text user "${REFERENCE}" (at -0.95 -3.168 90) (layer "B.Fab") hide
      (effects (font (size 0.7 0.7) (thickness 0.15)) (justify left bottom mirror))
    )
    (fp_rect (start -0.93 0.47) (end 0.93 -0.47) (layer "B.CrtYd") (width 0.05) (fill none))
    (fp_rect (start -0.5 0.25) (end 0.5 -0.25) (layer "B.Fab") (width 0.15) (fill none))
    (pad "1" smd roundrect (at -0.485 0 270) (size 0.59 0.64) (layers "B.Cu" "B.Paste" "B.Mask") (roundrect_rratio 0.25)
      (net 117 "SD_DATA1") (pintype "passive"))
    (pad "2" smd roundrect (at 0.485 0 270) (size 0.59 0.64) (layers "B.Cu" "B.Paste" "B.Mask") (roundrect_rratio 0.25)
      (net 251 "/Other Interfaces/SD_DATA1_R") (pintype "passive"))
  )
	(footprint "sa800u-baseboard-hw-footprints:R_0402_1005Metric" (layer "B.Cu")
    (tedit 5FD9C158)
    (at 119.9 93.8 -90)
    (descr "Resistor SMD 0402")
    (tags "resistor SMD 0402")
    (property "Author" "Antmicro")
    (property "License" "Apache-2.0")
    (property "MPN" "CR0402-FX-33R0GLF")
    (property "Manufacturer" "Bourns")
    (property "Sheetfile" "other-interfaces.kicad_sch")
    (property "Sheetname" "Other Interfaces")
    (property "Tolerance" "1%")
    (property "Val" "33R")
    (attr smd)
    (fp_text reference "R100" (at 0.87 -0.38 90) (layer "B.SilkS")
      (effects (font (size 0.7 0.7) (thickness 0.15)) (justify left bottom mirror))
    )
    (fp_text value "R_33R_0402" (at 0 -1.4 90) (layer "B.Fab")
      (effects (font (size 0.7 0.7) (thickness 0.15)) (justify left bottom mirror))
    )
    (fp_text user "Author: Antmicro" (at -0.95 -4.169 90) (layer "B.Fab") hide
      (effects (font (size 0.7 0.7) (thickness 0.15)) (justify left bottom mirror))
    )
    (fp_text user "${REFERENCE}" (at -0.95 -3.168 90) (layer "B.Fab") hide
      (effects (font (size 0.7 0.7) (thickness 0.15)) (justify left bottom mirror))
    )
    (fp_text user "License: Apache-2.0" (at -0.95 -5.169 90) (layer "B.Fab") hide
      (effects (font (size 0.7 0.7) (thickness 0.15)) (justify left bottom mirror))
    )
    (fp_rect (start -0.93 0.47) (end 0.93 -0.47) (layer "B.CrtYd") (width 0.05) (fill none))
    (fp_rect (start -0.5 0.25) (end 0.5 -0.25) (layer "B.Fab") (width 0.15) (fill none))
    (pad "1" smd roundrect (at -0.485 0 270) (size 0.59 0.64) (layers "B.Cu" "B.Paste" "B.Mask") (roundrect_rratio 0.25)
      (net 116 "SD_CLK") (pintype "passive"))
    (pad "2" smd roundrect (at 0.485 0 270) (size 0.59 0.64) (layers "B.Cu" "B.Paste" "B.Mask") (roundrect_rratio 0.25)
      (net 250 "/Other Interfaces/SD_CLK_R") (pintype "passive"))
  )
	(footprint "sa800u-baseboard-hw-footprints:R_0402_1005Metric" (layer "B.Cu")
    (tedit 5FD9C158)
    (at 120.9 93.8 -90)
    (descr "Resistor SMD 0402")
    (tags "resistor SMD 0402")
    (property "Author" "Antmicro")
    (property "License" "Apache-2.0")
    (property "MPN" "CR0402-FX-33R0GLF")
    (property "Manufacturer" "Bourns")
    (property "Sheetfile" "other-interfaces.kicad_sch")
    (property "Sheetname" "Other Interfaces")
    (property "Tolerance" "1%")
    (property "Val" "33R")
    (attr smd)
    (fp_text reference "R101" (at 0.87 -0.38 90) (layer "B.SilkS")
      (effects (font (size 0.7 0.7) (thickness 0.15)) (justify left bottom mirror))
    )
    (fp_text value "R_33R_0402" (at 0 -1.4 90) (layer "B.Fab")
      (effects (font (size 0.7 0.7) (thickness 0.15)) (justify left bottom mirror))
    )
    (fp_text user "${REFERENCE}" (at -0.95 -3.168 90) (layer "B.Fab") hide
      (effects (font (size 0.7 0.7) (thickness 0.15)) (justify left bottom mirror))
    )
    (fp_text user "License: Apache-2.0" (at -0.95 -5.169 90) (layer "B.Fab") hide
      (effects (font (size 0.7 0.7) (thickness 0.15)) (justify left bottom mirror))
    )
    (fp_text user "Author: Antmicro" (at -0.95 -4.169 90) (layer "B.Fab") hide
      (effects (font (size 0.7 0.7) (thickness 0.15)) (justify left bottom mirror))
    )
    (fp_rect (start -0.93 0.47) (end 0.93 -0.47) (layer "B.CrtYd") (width 0.05) (fill none))
    (fp_rect (start -0.5 0.25) (end 0.5 -0.25) (layer "B.Fab") (width 0.15) (fill none))
    (pad "1" smd roundrect (at -0.485 0 270) (size 0.59 0.64) (layers "B.Cu" "B.Paste" "B.Mask") (roundrect_rratio 0.25)
      (net 118 "SD_DATA0") (pintype "passive"))
    (pad "2" smd roundrect (at 0.485 0 270) (size 0.59 0.64) (layers "B.Cu" "B.Paste" "B.Mask") (roundrect_rratio 0.25)
      (net 252 "/Other Interfaces/SD_DATA0_R") (pintype "passive"))
  )
)
